(kicad_pcb
	(version 20260206)
	(generator "pcbnew")
	(generator_version "10.0")
	(general
		(thickness 1.6)
		(legacy_teardrops no)
	)
	(paper "A4")
	(title_block
		(title "panther-plus-userver — 13130-1b_20150205.brd")
		(comment 1 "Honey Badger (Wiwynn) / footprints 1411-1416 of 1509")
	)
	(layers
		(0 "F.Cu" signal "TOP")
		(4 "In1.Cu" signal "L2")
		(6 "In2.Cu" signal "L3")
		(8 "In3.Cu" signal "L4")
		(10 "In4.Cu" signal "L5")
		(12 "In5.Cu" signal "L6")
		(14 "In6.Cu" signal "L7")
		(16 "In7.Cu" signal "L8")
		(18 "In8.Cu" signal "L9")
		(20 "In9.Cu" signal "L10")
		(22 "In10.Cu" signal "L11")
		(2 "B.Cu" signal "BOTTOM")
		(9 "F.Adhes" user "F.Adhesive")
		(11 "B.Adhes" user "B.Adhesive")
		(13 "F.Paste" user "Package Geometry/Pastemask Top")
		(15 "B.Paste" user "Package Geometry/Pastemask Bottom")
		(5 "F.SilkS" user "Ref Des/Silkscreen Top")
		(7 "B.SilkS" user "Ref Des/Silkscreen Bottom")
		(1 "F.Mask" user "Board Geometry/Soldermask Top")
		(3 "B.Mask" user "Board Geometry/Soldermask Bottom")
		(17 "Dwgs.User" user "User.Drawings")
		(19 "Cmts.User" user "User.Comments")
		(21 "Eco1.User" user "User.Eco1")
		(23 "Eco2.User" user "User.Eco2")
		(25 "Edge.Cuts" user "Board Geometry/Outline")
		(27 "Margin" user)
		(31 "F.CrtYd" user "Package Geometry/Place Bound Top")
		(29 "B.CrtYd" user "Package Geometry/Place Bound Bottom")
		(35 "F.Fab" user "Ref Des/Assembly Top")
		(33 "B.Fab" user "Ref Des/Assembly Bottom")
	)
	(footprint ""
		(layer "B.Cu")
		(at 134.366 -48.641 90)
		(property "Reference" "R397"
			(at 0 0 90)
			(layer "B.SilkS")
			(hide yes)
			(effects
				(font
					(size 1.27 1.27)
				)
				(justify mirror)
			)
		)
		(property "Value" "0R2J-2-GP"
			(at -1.7907 -1.1176 90)
			(unlocked yes)
			(layer "B.Fab")
			(hide yes)
			(effects
				(font
					(size 1.016 1.016)
					(thickness 0.1524)
				)
				(justify mirror)
			)
		)
		(property "Device Type" "R402H16"
			(at -1.7907 -2.6416 90)
			(unlocked yes)
			(layer "B.Fab")
			(hide yes)
			(effects
				(font
					(size 1.016 1.016)
					(thickness 0.1524)
				)
				(justify mirror)
			)
		)
		(duplicate_pad_numbers_are_jumpers no)
		(fp_rect
			(start 0.381 0.8382)
			(end -0.381 -0.8382)
			(stroke
				(width 0)
				(type default)
			)
			(fill no)
			(layer "B.CrtYd")
		)
		(fp_rect
			(start 0.381 0.8382)
			(end -0.381 -0.8382)
			(stroke
				(width 0)
				(type default)
			)
			(fill no)
			(layer "B.Fab")
		)
		(pad "1" smd custom
			(at 0 -0.4318 270)
			(size 0.127 0.127)
			(layers "B.Cu" "B.Mask" "B.Paste")
			(net "REV_CPU_FPGA_IO0")
			(options
				(clearance outline)
				(anchor circle)
			)
			(primitives
				(gr_poly
					(pts
						(arc
							(start -0.2032 0.2794)
							(mid -0.239121 0.264521)
							(end -0.254 0.2286)
						)
						(arc
							(start -0.254 -0.2286)
							(mid -0.239121 -0.264521)
							(end -0.2032 -0.2794)
						)
						(arc
							(start 0.2032 -0.2794)
							(mid 0.239121 -0.264521)
							(end 0.254 -0.2286)
						)
						(arc
							(start 0.254 0.2286)
							(mid 0.239121 0.264521)
							(end 0.2032 0.2794)
						)
					)
					(width 0)
					(fill yes)
				)
			)
		)
		(pad "2" smd custom
			(at 0 0.4318 270)
			(size 0.127 0.127)
			(layers "B.Cu" "B.Mask" "B.Paste")
			(net "REV_CPU_FPGA_R_IO0")
			(options
				(clearance outline)
				(anchor circle)
			)
			(primitives
				(gr_poly
					(pts
						(arc
							(start -0.2032 0.2794)
							(mid -0.239121 0.264521)
							(end -0.254 0.2286)
						)
						(arc
							(start -0.254 -0.2286)
							(mid -0.239121 -0.264521)
							(end -0.2032 -0.2794)
						)
						(arc
							(start 0.2032 -0.2794)
							(mid 0.239121 -0.264521)
							(end 0.254 -0.2286)
						)
						(arc
							(start 0.254 0.2286)
							(mid 0.239121 0.264521)
							(end 0.2032 0.2794)
						)
					)
					(width 0)
					(fill yes)
				)
			)
		)
	)
	(footprint ""
		(layer "B.Cu")
		(at 168.783 -12.600178 180)
		(property "Reference" "C332"
			(at 0 0 0)
			(layer "B.SilkS")
			(hide yes)
			(effects
				(font
					(size 1.27 1.27)
				)
				(justify mirror)
			)
		)
		(property "Value" "SCD1U16V2KX-3GP"
			(at -1.8923 -1.2065 180)
			(unlocked yes)
			(layer "B.Fab")
			(hide yes)
			(effects
				(font
					(size 1.016 1.016)
					(thickness 0.1524)
				)
				(justify mirror)
			)
		)
		(property "Device Type" "C402H22"
			(at -1.8923 -2.7305 180)
			(unlocked yes)
			(layer "B.Fab")
			(hide yes)
			(effects
				(font
					(size 1.016 1.016)
					(thickness 0.1524)
				)
				(justify mirror)
			)
		)
		(duplicate_pad_numbers_are_jumpers no)
		(fp_rect
			(start 0.381 0.7366)
			(end -0.381 -0.7366)
			(stroke
				(width 0)
				(type default)
			)
			(fill no)
			(layer "B.CrtYd")
		)
		(fp_rect
			(start 0.381 0.7366)
			(end -0.381 -0.7366)
			(stroke
				(width 0)
				(type default)
			)
			(fill no)
			(layer "B.Fab")
		)
		(pad "1" smd custom
			(at 0 -0.4572)
			(size 0.1143 0.1143)
			(layers "B.Cu" "B.Mask" "B.Paste")
			(net "PV_VDDR")
			(options
				(clearance outline)
				(anchor circle)
			)
			(primitives
				(gr_poly
					(pts
						(arc
							(start -0.254 0.1778)
							(mid -0.239121 0.213721)
							(end -0.2032 0.2286)
						)
						(arc
							(start 0.2032 0.2286)
							(mid 0.239121 0.213721)
							(end 0.254 0.1778)
						)
						(arc
							(start 0.254 -0.1778)
							(mid 0.239121 -0.213721)
							(end 0.2032 -0.2286)
						)
						(arc
							(start -0.2032 -0.2286)
							(mid -0.239121 -0.213721)
							(end -0.254 -0.1778)
						)
					)
					(width 0)
					(fill yes)
				)
			)
		)
		(pad "2" smd custom
			(at 0 0.4572)
			(size 0.1143 0.1143)
			(layers "B.Cu" "B.Mask" "B.Paste")
			(net "GND")
			(options
				(clearance outline)
				(anchor circle)
			)
			(primitives
				(gr_poly
					(pts
						(arc
							(start -0.254 0.1778)
							(mid -0.239121 0.213721)
							(end -0.2032 0.2286)
						)
						(arc
							(start 0.2032 0.2286)
							(mid 0.239121 0.213721)
							(end 0.254 0.1778)
						)
						(arc
							(start 0.254 -0.1778)
							(mid 0.239121 -0.213721)
							(end 0.2032 -0.2286)
						)
						(arc
							(start -0.2032 -0.2286)
							(mid -0.239121 -0.213721)
							(end -0.254 -0.1778)
						)
					)
					(width 0)
					(fill yes)
				)
			)
		)
	)
	(footprint ""
		(layer "B.Cu")
		(at 35.941 -44.577)
		(property "Reference" "X2"
			(at 0 0 0)
			(layer "B.SilkS")
			(hide yes)
			(effects
				(font
					(size 1.27 1.27)
				)
				(justify mirror)
			)
		)
		(property "Value" "XTAL-14D31818MHZ-1-GP"
			(at 2.794 1.4478 0)
			(unlocked yes)
			(layer "B.Fab")
			(hide yes)
			(effects
				(font
					(size 1.016 1.016)
					(thickness 0.1524)
				)
				(justify mirror)
			)
		)
		(property "Device Type" "SMD49-5032H54"
			(at 2.794 -0.0762 0)
			(unlocked yes)
			(layer "B.Fab")
			(hide yes)
			(effects
				(font
					(size 1.016 1.016)
					(thickness 0.1524)
				)
				(justify mirror)
			)
		)
		(duplicate_pad_numbers_are_jumpers no)
		(fp_rect
			(start 1.8542 2.9972)
			(end -1.8542 -2.9972)
			(stroke
				(width 0)
				(type default)
			)
			(fill no)
			(layer "B.CrtYd")
		)
		(fp_rect
			(start 1.8542 2.9972)
			(end -1.8542 -2.9972)
			(stroke
				(width 0)
				(type default)
			)
			(fill no)
			(layer "B.Fab")
		)
		(pad "1" smd rect
			(at 0 -1.911096 180)
			(size 2.2606 1.9304)
			(layers "B.Cu" "B.Mask" "B.Paste")
			(net "XTAL_CLK_GEN_IN")
		)
		(pad "2" smd rect
			(at 0 1.911096 180)
			(size 2.2606 1.9304)
			(layers "B.Cu" "B.Mask" "B.Paste")
			(net "XTAL_CLK_GEN_OUT")
		)
		(zone
			(layer "B.Cu")
			(hatch none 0.5)
			(connect_pads
				(clearance 0)
			)
			(min_thickness 0.25)
			(keepout
				(tracks not_allowed)
				(vias allowed)
				(pads allowed)
				(copperpour not_allowed)
				(footprints allowed)
			)
			(placement
				(enabled no)
				(sheetname "")
			)
			(fill
				(thermal_gap 0.5)
				(thermal_bridge_width 0.5)
				(island_removal_mode 0)
			)
			(polygon
				(pts
					(xy 34.8107 -45.522896) (xy 34.3408 -45.522896) (xy 34.3408 -47.453296) (xy 34.8107 -47.453296)
				)
			)
		)
		(zone
			(layer "B.Cu")
			(hatch none 0.5)
			(connect_pads
				(clearance 0)
			)
			(min_thickness 0.25)
			(keepout
				(tracks allowed)
				(vias not_allowed)
				(pads allowed)
				(copperpour not_allowed)
				(footprints allowed)
			)
			(placement
				(enabled no)
				(sheetname "")
			)
			(fill
				(thermal_gap 0.5)
				(thermal_bridge_width 0.5)
				(island_removal_mode 0)
			)
			(polygon
				(pts
					(xy 34.8107 -45.522896) (xy 34.3408 -45.522896) (xy 34.3408 -47.453296) (xy 34.8107 -47.453296)
				)
			)
		)
		(zone
			(layer "B.Cu")
			(hatch none 0.5)
			(connect_pads
				(clearance 0)
			)
			(min_thickness 0.25)
			(keepout
				(tracks not_allowed)
				(vias allowed)
				(pads allowed)
				(copperpour not_allowed)
				(footprints allowed)
			)
			(placement
				(enabled no)
				(sheetname "")
			)
			(fill
				(thermal_gap 0.5)
				(thermal_bridge_width 0.5)
				(island_removal_mode 0)
			)
			(polygon
				(pts
					(xy 34.8107 -41.700704) (xy 34.3408 -41.700704) (xy 34.3408 -43.631104) (xy 34.8107 -43.631104)
				)
			)
		)
		(zone
			(layer "B.Cu")
			(hatch none 0.5)
			(connect_pads
				(clearance 0)
			)
			(min_thickness 0.25)
			(keepout
				(tracks allowed)
				(vias not_allowed)
				(pads allowed)
				(copperpour not_allowed)
				(footprints allowed)
			)
			(placement
				(enabled no)
				(sheetname "")
			)
			(fill
				(thermal_gap 0.5)
				(thermal_bridge_width 0.5)
				(island_removal_mode 0)
			)
			(polygon
				(pts
					(xy 34.8107 -41.700704) (xy 34.3408 -41.700704) (xy 34.3408 -43.631104) (xy 34.8107 -43.631104)
				)
			)
		)
		(zone
			(layer "B.Cu")
			(hatch none 0.5)
			(connect_pads
				(clearance 0)
			)
			(min_thickness 0.25)
			(keepout
				(tracks allowed)
				(vias not_allowed)
				(pads allowed)
				(copperpour not_allowed)
				(footprints allowed)
			)
			(placement
				(enabled no)
				(sheetname "")
			)
			(fill
				(thermal_gap 0.5)
				(thermal_bridge_width 0.5)
				(island_removal_mode 0)
			)
			(polygon
				(pts
					(xy 37.0713 -45.522896) (xy 37.0713 -43.631104) (xy 34.8107 -43.631104) (xy 34.8107 -45.522896)
				)
			)
		)
		(zone
			(layer "B.Cu")
			(hatch none 0.5)
			(connect_pads
				(clearance 0)
			)
			(min_thickness 0.25)
			(keepout
				(tracks allowed)
				(vias not_allowed)
				(pads allowed)
				(copperpour not_allowed)
				(footprints allowed)
			)
			(placement
				(enabled no)
				(sheetname "")
			)
			(fill
				(thermal_gap 0.5)
				(thermal_bridge_width 0.5)
				(island_removal_mode 0)
			)
			(polygon
				(pts
					(xy 37.5412 -45.522896) (xy 37.0713 -45.522896) (xy 37.0713 -47.453296) (xy 37.5412 -47.453296)
				)
			)
		)
		(zone
			(layer "B.Cu")
			(hatch none 0.5)
			(connect_pads
				(clearance 0)
			)
			(min_thickness 0.25)
			(keepout
				(tracks not_allowed)
				(vias allowed)
				(pads allowed)
				(copperpour not_allowed)
				(footprints allowed)
			)
			(placement
				(enabled no)
				(sheetname "")
			)
			(fill
				(thermal_gap 0.5)
				(thermal_bridge_width 0.5)
				(island_removal_mode 0)
			)
			(polygon
				(pts
					(xy 37.5412 -45.522896) (xy 37.0713 -45.522896) (xy 37.0713 -47.453296) (xy 37.5412 -47.453296)
				)
			)
		)
		(zone
			(layer "B.Cu")
			(hatch none 0.5)
			(connect_pads
				(clearance 0)
			)
			(min_thickness 0.25)
			(keepout
				(tracks allowed)
				(vias not_allowed)
				(pads allowed)
				(copperpour not_allowed)
				(footprints allowed)
			)
			(placement
				(enabled no)
				(sheetname "")
			)
			(fill
				(thermal_gap 0.5)
				(thermal_bridge_width 0.5)
				(island_removal_mode 0)
			)
			(polygon
				(pts
					(xy 37.5412 -41.700704) (xy 37.0713 -41.700704) (xy 37.0713 -43.631104) (xy 37.5412 -43.631104)
				)
			)
		)
		(zone
			(layer "B.Cu")
			(hatch none 0.5)
			(connect_pads
				(clearance 0)
			)
			(min_thickness 0.25)
			(keepout
				(tracks not_allowed)
				(vias allowed)
				(pads allowed)
				(copperpour not_allowed)
				(footprints allowed)
			)
			(placement
				(enabled no)
				(sheetname "")
			)
			(fill
				(thermal_gap 0.5)
				(thermal_bridge_width 0.5)
				(island_removal_mode 0)
			)
			(polygon
				(pts
					(xy 37.5412 -41.700704) (xy 37.0713 -41.700704) (xy 37.0713 -43.631104) (xy 37.5412 -43.631104)
				)
			)
		)
	)
	(footprint ""
		(layer "B.Cu")
		(at 197.231 -66.802 90)
		(property "Reference" "R85"
			(at 0 0 90)
			(layer "B.SilkS")
			(hide yes)
			(effects
				(font
					(size 1.27 1.27)
				)
				(justify mirror)
			)
		)
		(property "Value" "300R2F-GP"
			(at -1.7907 -1.1176 90)
			(unlocked yes)
			(layer "B.Fab")
			(hide yes)
			(effects
				(font
					(size 1.016 1.016)
					(thickness 0.1524)
				)
				(justify mirror)
			)
		)
		(property "Device Type" "R402H16"
			(at -1.7907 -2.6416 90)
			(unlocked yes)
			(layer "B.Fab")
			(hide yes)
			(effects
				(font
					(size 1.016 1.016)
					(thickness 0.1524)
				)
				(justify mirror)
			)
		)
		(duplicate_pad_numbers_are_jumpers no)
		(fp_rect
			(start 0.381 0.8382)
			(end -0.381 -0.8382)
			(stroke
				(width 0)
				(type default)
			)
			(fill no)
			(layer "B.CrtYd")
		)
		(fp_rect
			(start 0.381 0.8382)
			(end -0.381 -0.8382)
			(stroke
				(width 0)
				(type default)
			)
			(fill no)
			(layer "B.Fab")
		)
		(pad "1" smd custom
			(at 0 -0.4318 270)
			(size 0.127 0.127)
			(layers "B.Cu" "B.Mask" "B.Paste")
			(net "P3V3")
			(options
				(clearance outline)
				(anchor circle)
			)
			(primitives
				(gr_poly
					(pts
						(arc
							(start -0.2032 0.2794)
							(mid -0.239121 0.264521)
							(end -0.254 0.2286)
						)
						(arc
							(start -0.254 -0.2286)
							(mid -0.239121 -0.264521)
							(end -0.2032 -0.2794)
						)
						(arc
							(start 0.2032 -0.2794)
							(mid 0.239121 -0.264521)
							(end 0.254 -0.2286)
						)
						(arc
							(start 0.254 0.2286)
							(mid 0.239121 0.264521)
							(end 0.2032 0.2794)
						)
					)
					(width 0)
					(fill yes)
				)
			)
		)
		(pad "2" smd custom
			(at 0 0.4318 270)
			(size 0.127 0.127)
			(layers "B.Cu" "B.Mask" "B.Paste")
			(net "BEEP_LED")
			(options
				(clearance outline)
				(anchor circle)
			)
			(primitives
				(gr_poly
					(pts
						(arc
							(start -0.2032 0.2794)
							(mid -0.239121 0.264521)
							(end -0.254 0.2286)
						)
						(arc
							(start -0.254 -0.2286)
							(mid -0.239121 -0.264521)
							(end -0.2032 -0.2794)
						)
						(arc
							(start 0.2032 -0.2794)
							(mid 0.239121 -0.264521)
							(end 0.254 -0.2286)
						)
						(arc
							(start 0.254 0.2286)
							(mid 0.239121 0.264521)
							(end 0.2032 0.2794)
						)
					)
					(width 0)
					(fill yes)
				)
			)
		)
	)
	(footprint ""
		(layer "B.Cu")
		(at 53.467 -19.558 -90)
		(property "Reference" "C231"
			(at 0 0 90)
			(layer "B.SilkS")
			(hide yes)
			(effects
				(font
					(size 1.27 1.27)
				)
				(justify mirror)
			)
		)
		(property "Value" "SCD1U16V2KX-3GP"
			(at -1.1811 -2.7051 270)
			(unlocked yes)
			(layer "B.Fab")
			(hide yes)
			(effects
				(font
					(size 1.016 1.016)
					(thickness 0.1524)
				)
				(justify mirror)
			)
		)
		(property "Device Type" "C402H22"
			(at -1.1811 -4.2291 270)
			(unlocked yes)
			(layer "B.Fab")
			(hide yes)
			(effects
				(font
					(size 1.016 1.016)
					(thickness 0.1524)
				)
				(justify mirror)
			)
		)
		(duplicate_pad_numbers_are_jumpers no)
		(fp_rect
			(start 0.381 0.7366)
			(end -0.381 -0.7366)
			(stroke
				(width 0)
				(type default)
			)
			(fill no)
			(layer "B.CrtYd")
		)
		(fp_rect
			(start 0.381 0.7366)
			(end -0.381 -0.7366)
			(stroke
				(width 0)
				(type default)
			)
			(fill no)
			(layer "B.Fab")
		)
		(pad "1" smd custom
			(at 0 -0.4572 90)
			(size 0.1143 0.1143)
			(layers "B.Cu" "B.Mask" "B.Paste")
			(net "P3V3")
			(options
				(clearance outline)
				(anchor circle)
			)
			(primitives
				(gr_poly
					(pts
						(arc
							(start -0.254 0.1778)
							(mid -0.239121 0.213721)
							(end -0.2032 0.2286)
						)
						(arc
							(start 0.2032 0.2286)
							(mid 0.239121 0.213721)
							(end 0.254 0.1778)
						)
						(arc
							(start 0.254 -0.1778)
							(mid 0.239121 -0.213721)
							(end 0.2032 -0.2286)
						)
						(arc
							(start -0.2032 -0.2286)
							(mid -0.239121 -0.213721)
							(end -0.254 -0.1778)
						)
					)
					(width 0)
					(fill yes)
				)
			)
		)
		(pad "2" smd custom
			(at 0 0.4572 90)
			(size 0.1143 0.1143)
			(layers "B.Cu" "B.Mask" "B.Paste")
			(net "GND")
			(options
				(clearance outline)
				(anchor circle)
			)
			(primitives
				(gr_poly
					(pts
						(arc
							(start -0.254 0.1778)
							(mid -0.239121 0.213721)
							(end -0.2032 0.2286)
						)
						(arc
							(start 0.2032 0.2286)
							(mid 0.239121 0.213721)
							(end 0.254 0.1778)
						)
						(arc
							(start 0.254 -0.1778)
							(mid 0.239121 -0.213721)
							(end 0.2032 -0.2286)
						)
						(arc
							(start -0.2032 -0.2286)
							(mid -0.239121 -0.213721)
							(end -0.254 -0.1778)
						)
					)
					(width 0)
					(fill yes)
				)
			)
		)
	)
	(footprint ""
		(layer "B.Cu")
		(at 83.3374 -28.9052 180)
		(property "Reference" "R364"
			(at 0 0 0)
			(layer "B.SilkS")
			(hide yes)
			(effects
				(font
					(size 1.27 1.27)
				)
				(justify mirror)
			)
		)
		(property "Value" "402R2F-GP"
			(at -0.064008 -3.993896 180)
			(unlocked yes)
			(layer "B.Fab")
			(hide yes)
			(effects
				(font
					(size 1.016 1.016)
					(thickness 0.1524)
				)
				(justify mirror)
			)
		)
		(property "Device Type" "R402H16"
			(at -0.064008 -5.517896 180)
			(unlocked yes)
			(layer "B.Fab")
			(hide yes)
			(effects
				(font
					(size 1.016 1.016)
					(thickness 0.1524)
				)
				(justify mirror)
			)
		)
		(duplicate_pad_numbers_are_jumpers no)
		(fp_rect
			(start 0.381 0.8382)
			(end -0.381 -0.8382)
			(stroke
				(width 0)
				(type default)
			)
			(fill no)
			(layer "B.CrtYd")
		)
		(fp_rect
			(start 0.381 0.8382)
			(end -0.381 -0.8382)
			(stroke
				(width 0)
				(type default)
			)
			(fill no)
			(layer "B.Fab")
		)
		(pad "1" smd custom
			(at 0 -0.4318)
			(size 0.127 0.127)
			(layers "B.Cu" "B.Mask" "B.Paste")
			(net "SATA2_OBS_P")
			(options
				(clearance outline)
				(anchor circle)
			)
			(primitives
				(gr_poly
					(pts
						(arc
							(start -0.2032 0.2794)
							(mid -0.239121 0.264521)
							(end -0.254 0.2286)
						)
						(arc
							(start -0.254 -0.2286)
							(mid -0.239121 -0.264521)
							(end -0.2032 -0.2794)
						)
						(arc
							(start 0.2032 -0.2794)
							(mid 0.239121 -0.264521)
							(end 0.254 -0.2286)
						)
						(arc
							(start 0.254 0.2286)
							(mid 0.239121 0.264521)
							(end 0.2032 0.2794)
						)
					)
					(width 0)
					(fill yes)
				)
			)
		)
		(pad "2" smd custom
			(at 0 0.4318)
			(size 0.127 0.127)
			(layers "B.Cu" "B.Mask" "B.Paste")
			(net "SATA2_OBS_N")
			(options
				(clearance outline)
				(anchor circle)
			)
			(primitives
				(gr_poly
					(pts
						(arc
							(start -0.2032 0.2794)
							(mid -0.239121 0.264521)
							(end -0.254 0.2286)
						)
						(arc
							(start -0.254 -0.2286)
							(mid -0.239121 -0.264521)
							(end -0.2032 -0.2794)
						)
						(arc
							(start 0.2032 -0.2794)
							(mid 0.239121 -0.264521)
							(end 0.254 -0.2286)
						)
						(arc
							(start 0.254 0.2286)
							(mid 0.239121 0.264521)
							(end 0.2032 0.2794)
						)
					)
					(width 0)
					(fill yes)
				)
			)
		)
	)
)
